# T6G (Grand Teton) — schematic netlist excerpt (pin names and nets, part order shuffled) for the footprints in the layout excerpt that follows; sources: Cadence DE-HDL packaged netlist, KiCad conversion of 04192023_DAF0TMB3IC0_F0TG_MB_C_brd_V02_OCP.brd

PR8012  Q_RES  0 5% CHIP  pkg 0402LF  page 217 : A = SVID_PVDDCR_CPU1_P1_SVD_R ; B = SVID_PVDDCR_CPU1_P1_SVD_R1
R554  Q_RES  100K 1% CHIP  pkg 0402LF  page 188 : A = P12V_AUX ; B = SW_P3V3_EN_N

(kicad_pcb
	(version 20260206)
	(generator "pcbnew")
	(generator_version "10.0")
	(general
		(thickness 1.6)
		(legacy_teardrops no)
	)
	(paper "A4")
	(title_block
		(title "04192023_DAF0TMB3IC0_F0TG_MB_C_brd_V02_OCP.brd")
		(comment 1 "Grand Teton / footprints 1248-1249 of 8354")
	)
	(layers
		(0 "F.Cu" signal "TOP")
		(4 "In1.Cu" signal "GND")
		(6 "In2.Cu" signal "IN1")
		(8 "In3.Cu" signal "GND1")
		(10 "In4.Cu" signal "IN2")
		(12 "In5.Cu" signal "GND2")
		(14 "In6.Cu" signal "IN3")
		(16 "In7.Cu" signal "GND3")
		(18 "In8.Cu" signal "VCC")
		(20 "In9.Cu" signal "VCC1")
		(22 "In10.Cu" signal "GND4")
		(24 "In11.Cu" signal "IN4")
		(26 "In12.Cu" signal "GND5")
		(28 "In13.Cu" signal "IN5")
		(30 "In14.Cu" signal "GND6")
		(32 "In15.Cu" signal "IN6")
		(34 "In16.Cu" signal "GND7")
		(2 "B.Cu" signal "BOTTOM")
		(9 "F.Adhes" user "F.Adhesive")
		(11 "B.Adhes" user "B.Adhesive")
		(13 "F.Paste" user "Package Geometry/Pastemask Top")
		(15 "B.Paste" user "Package Geometry/Pastemask Bottom")
		(5 "F.SilkS" user "Ref Des/Silkscreen Top")
		(7 "B.SilkS" user "Ref Des/Silkscreen Bottom")
		(1 "F.Mask" user "Board Geometry/Soldermask Top")
		(3 "B.Mask" user "Board Geometry/Soldermask Bottom")
		(17 "Dwgs.User" user "User.Drawings")
		(19 "Cmts.User" user "User.Comments")
		(21 "Eco1.User" user "User.Eco1")
		(23 "Eco2.User" user "User.Eco2")
		(25 "Edge.Cuts" user "Board Geometry/Outline")
		(27 "Margin" user)
		(31 "F.CrtYd" user "Package Geometry/Place Bound Top")
		(29 "B.CrtYd" user "Package Geometry/Place Bound Bottom")
		(35 "F.Fab" user "Ref Des/Assembly Top")
		(33 "B.Fab" user "Ref Des/Assembly Bottom")
	)
	(footprint ""
		(layer "F.Cu")
		(at 205.74 -135.763)
		(property "Reference" "R554"
			(at 0 0 0)
			(layer "F.SilkS")
			(hide yes)
			(effects
				(font
					(size 1.27 1.27)
				)
			)
		)
		(property "Value" ""
			(at 0 0 0)
			(layer "F.Fab")
			(effects
				(font
					(size 1.27 1.27)
				)
			)
		)
		(duplicate_pad_numbers_are_jumpers no)
		(fp_line
			(start -0.7874 -0.4064)
			(end 0.7874 -0.4064)
			(stroke
				(width 0.1524)
				(type default)
			)
			(layer "F.SilkS")
		)
		(fp_line
			(start -0.7874 0.4064)
			(end -0.7874 -0.4064)
			(stroke
				(width 0.1524)
				(type default)
			)
			(layer "F.SilkS")
		)
		(fp_line
			(start 0.7874 -0.4064)
			(end 0.7874 0.4064)
			(stroke
				(width 0.1524)
				(type default)
			)
			(layer "F.SilkS")
		)
		(fp_line
			(start 0.7874 0.4064)
			(end -0.7874 0.4064)
			(stroke
				(width 0.1524)
				(type default)
			)
			(layer "F.SilkS")
		)
		(fp_line
			(start -0.67945 -0.305054)
			(end -0.12065 -0.305054)
			(stroke
				(width 0.1)
				(type default)
			)
			(layer "F.Fab")
		)
		(fp_line
			(start -0.67945 0.3048)
			(end -0.67945 -0.305054)
			(stroke
				(width 0.1)
				(type default)
			)
			(layer "F.Fab")
		)
		(fp_line
			(start -0.12065 -0.305054)
			(end -0.12065 -0.2794)
			(stroke
				(width 0.1)
				(type default)
			)
			(layer "F.Fab")
		)
		(fp_line
			(start -0.12065 -0.2794)
			(end 0.12065 -0.2794)
			(stroke
				(width 0.1)
				(type default)
			)
			(layer "F.Fab")
		)
		(fp_line
			(start -0.12065 0.2794)
			(end -0.12065 0.3048)
			(stroke
				(width 0.1)
				(type default)
			)
			(layer "F.Fab")
		)
		(fp_line
			(start -0.12065 0.3048)
			(end -0.67945 0.3048)
			(stroke
				(width 0.1)
				(type default)
			)
			(layer "F.Fab")
		)
		(fp_line
			(start 0.120396 0.2794)
			(end -0.12065 0.2794)
			(stroke
				(width 0.1)
				(type default)
			)
			(layer "F.Fab")
		)
		(fp_line
			(start 0.120396 0.3048)
			(end 0.120396 0.2794)
			(stroke
				(width 0.1)
				(type default)
			)
			(layer "F.Fab")
		)
		(fp_line
			(start 0.12065 -0.3048)
			(end 0.67945 -0.3048)
			(stroke
				(width 0.1)
				(type default)
			)
			(layer "F.Fab")
		)
		(fp_line
			(start 0.12065 -0.2794)
			(end 0.12065 -0.3048)
			(stroke
				(width 0.1)
				(type default)
			)
			(layer "F.Fab")
		)
		(fp_line
			(start 0.67945 -0.3048)
			(end 0.67945 0.3048)
			(stroke
				(width 0.1)
				(type default)
			)
			(layer "F.Fab")
		)
		(fp_line
			(start 0.67945 0.3048)
			(end 0.120396 0.3048)
			(stroke
				(width 0.1)
				(type default)
			)
			(layer "F.Fab")
		)
		(pad "1" smd circle
			(at -0.40005 0)
			(size 0 0)
			(layers "F.Cu" "F.Mask" "F.Paste")
			(net "P12V_AUX")
		)
		(pad "2" smd circle
			(at 0.40005 0)
			(size 0 0)
			(layers "F.Cu" "F.Mask" "F.Paste")
			(net "SW_P3V3_EN_N")
		)
	)
	(footprint ""
		(layer "F.Cu")
		(at 24.765 -361.061)
		(property "Reference" "PR8012"
			(at 0 0 0)
			(layer "F.SilkS")
			(hide yes)
			(effects
				(font
					(size 1.27 1.27)
				)
			)
		)
		(property "Value" ""
			(at 0 0 0)
			(layer "F.Fab")
			(effects
				(font
					(size 1.27 1.27)
				)
			)
		)
		(duplicate_pad_numbers_are_jumpers no)
		(fp_line
			(start -0.7874 -0.4064)
			(end 0.7874 -0.4064)
			(stroke
				(width 0.1524)
				(type default)
			)
			(layer "F.SilkS")
		)
		(fp_line
			(start -0.7874 0.4064)
			(end -0.7874 -0.4064)
			(stroke
				(width 0.1524)
				(type default)
			)
			(layer "F.SilkS")
		)
		(fp_line
			(start 0.7874 -0.4064)
			(end 0.7874 0.4064)
			(stroke
				(width 0.1524)
				(type default)
			)
			(layer "F.SilkS")
		)
		(fp_line
			(start 0.7874 0.4064)
			(end -0.7874 0.4064)
			(stroke
				(width 0.1524)
				(type default)
			)
			(layer "F.SilkS")
		)
		(fp_line
			(start -0.67945 -0.305054)
			(end -0.12065 -0.305054)
			(stroke
				(width 0.1)
				(type default)
			)
			(layer "F.Fab")
		)
		(fp_line
			(start -0.67945 0.3048)
			(end -0.67945 -0.305054)
			(stroke
				(width 0.1)
				(type default)
			)
			(layer "F.Fab")
		)
		(fp_line
			(start -0.12065 -0.305054)
			(end -0.12065 -0.2794)
			(stroke
				(width 0.1)
				(type default)
			)
			(layer "F.Fab")
		)
		(fp_line
			(start -0.12065 -0.2794)
			(end 0.12065 -0.2794)
			(stroke
				(width 0.1)
				(type default)
			)
			(layer "F.Fab")
		)
		(fp_line
			(start -0.12065 0.2794)
			(end -0.12065 0.3048)
			(stroke
				(width 0.1)
				(type default)
			)
			(layer "F.Fab")
		)
		(fp_line
			(start -0.12065 0.3048)
			(end -0.67945 0.3048)
			(stroke
				(width 0.1)
				(type default)
			)
			(layer "F.Fab")
		)
		(fp_line
			(start 0.120396 0.2794)
			(end -0.12065 0.2794)
			(stroke
				(width 0.1)
				(type default)
			)
			(layer "F.Fab")
		)
		(fp_line
			(start 0.120396 0.3048)
			(end 0.120396 0.2794)
			(stroke
				(width 0.1)
				(type default)
			)
			(layer "F.Fab")
		)
		(fp_line
			(start 0.12065 -0.3048)
			(end 0.67945 -0.3048)
			(stroke
				(width 0.1)
				(type default)
			)
			(layer "F.Fab")
		)
		(fp_line
			(start 0.12065 -0.2794)
			(end 0.12065 -0.3048)
			(stroke
				(width 0.1)
				(type default)
			)
			(layer "F.Fab")
		)
		(fp_line
			(start 0.67945 -0.3048)
			(end 0.67945 0.3048)
			(stroke
				(width 0.1)
				(type default)
			)
			(layer "F.Fab")
		)
		(fp_line
			(start 0.67945 0.3048)
			(end 0.120396 0.3048)
			(stroke
				(width 0.1)
				(type default)
			)
			(layer "F.Fab")
		)
		(pad "1" smd circle
			(at -0.40005 0)
			(size 0 0)
			(layers "F.Cu" "F.Mask" "F.Paste")
			(net "SVID_PVDDCR_CPU1_P1_SVD_R")
		)
		(pad "2" smd circle
			(at 0.40005 0)
			(size 0 0)
			(layers "F.Cu" "F.Mask" "F.Paste")
			(net "SVID_PVDDCR_CPU1_P1_SVD_R1")
		)
	)
)
